# TIMECARD (Time Appliance Project (Time Card)) — schematic netlist excerpt (pin names and nets, part order shuffled) for the footprints in the layout excerpt that follows; sources: Cadence DE-HDL packaged netlist, KiCad conversion of R4006-B0001-02_R01.brd

TP61  TP_PIONT  pkg TP010CT020B030_PTH  page 20 : \1\ = UNNAMED_9_BNO080LGA28_I29_HCS
R442  RESISTOR  5.1KOHM 1%  pkg SMC_0402R_H016  page 24 : \1\ = UNNAMED_524_CONNUSB14PGH4FRATH_ ; \2\ = SG

(kicad_pcb
	(version 20260206)
	(generator "pcbnew")
	(generator_version "10.0")
	(general
		(thickness 1.6)
		(legacy_teardrops no)
	)
	(paper "A4")
	(title_block
		(title "timecard-production-celestica-r4006 — R4006-B0001-02_R01.brd")
		(comment 1 "Time Appliance Project (Time Card) / footprints 100-101 of 1113")
	)
	(layers
		(0 "F.Cu" signal "TOP")
		(4 "In1.Cu" signal "L02_GND1")
		(6 "In2.Cu" signal "L03_SIG1")
		(8 "In3.Cu" signal "L04_GND2")
		(10 "In4.Cu" signal "L05_VCC1")
		(12 "In5.Cu" signal "L06_VCC2")
		(14 "In6.Cu" signal "L07_GND3")
		(16 "In7.Cu" signal "L08_SIG2")
		(18 "In8.Cu" signal "L09_GND4")
		(2 "B.Cu" signal "BOTTOM")
		(9 "F.Adhes" user "F.Adhesive")
		(11 "B.Adhes" user "B.Adhesive")
		(13 "F.Paste" user "Package Geometry/Pastemask Top")
		(15 "B.Paste" user "Package Geometry/Pastemask Bottom")
		(5 "F.SilkS" user "Ref Des/Silkscreen Top")
		(7 "B.SilkS" user "Ref Des/Silkscreen Bottom")
		(1 "F.Mask" user "Board Geometry/Soldermask Top")
		(3 "B.Mask" user "Board Geometry/Soldermask Bottom")
		(17 "Dwgs.User" user "User.Drawings")
		(19 "Cmts.User" user "User.Comments")
		(21 "Eco1.User" user "User.Eco1")
		(23 "Eco2.User" user "User.Eco2")
		(25 "Edge.Cuts" user "Board Geometry/Outline")
		(27 "Margin" user)
		(31 "F.CrtYd" user "Package Geometry/Place Bound Top")
		(29 "B.CrtYd" user "Package Geometry/Place Bound Bottom")
		(35 "F.Fab" user "Ref Des/Assembly Top")
		(33 "B.Fab" user "Ref Des/Assembly Bottom")
	)
	(footprint ""
		(layer "F.Cu")
		(at 15.113 -90.805 90)
		(property "Reference" "R442"
			(at 1.27 -1.10363 90)
			(unlocked yes)
			(layer "F.SilkS")
			(effects
				(font
					(size 0.7874 0.5842)
					(thickness 0.1524)
				)
			)
		)
		(property "Value" "VAL*"
			(at 0.02032 2.13233 90)
			(unlocked yes)
			(layer "F.Fab")
			(hide yes)
			(effects
				(font
					(size 0.7874 0.5842)
					(thickness 0.1524)
				)
			)
		)
		(property "Tolerance" "TOL*"
			(at 0.044704 3.05435 90)
			(unlocked yes)
			(layer "Cmts.User")
			(hide yes)
			(effects
				(font
					(size 0.7874 0.5842)
					(thickness 0.1524)
				)
			)
		)
		(property "User Part Number" "PARTNUM*"
			(at 0.02032 4.024884 90)
			(unlocked yes)
			(layer "Cmts.User")
			(hide yes)
			(effects
				(font
					(size 0.7874 0.5842)
					(thickness 0.1524)
				)
			)
		)
		(property "Device Type" "RESISTOR-G155-05101-01,5.1KOHMA"
			(at 0.008382 1.210564 90)
			(unlocked yes)
			(layer "F.Fab")
			(hide yes)
			(effects
				(font
					(size 0.7874 0.5842)
					(thickness 0.1524)
				)
			)
		)
		(duplicate_pad_numbers_are_jumpers no)
		(fp_line
			(start 1.143 -0.5588)
			(end -1.143 -0.5588)
			(stroke
				(width 0.1)
				(type default)
			)
			(layer "F.SilkS")
		)
		(fp_line
			(start -1.143 -0.5588)
			(end -1.143 0.5588)
			(stroke
				(width 0.1)
				(type default)
			)
			(layer "F.SilkS")
		)
		(fp_line
			(start 1.143 0.5588)
			(end 1.143 -0.5588)
			(stroke
				(width 0.1)
				(type default)
			)
			(layer "F.SilkS")
		)
		(fp_line
			(start -1.143 0.5588)
			(end 1.143 0.5588)
			(stroke
				(width 0.1)
				(type default)
			)
			(layer "F.SilkS")
		)
		(fp_poly
			(pts
				(xy -1.143 0.5588) (xy 1.143 0.5588) (xy 1.143 -0.5588) (xy -1.143 -0.5588)
			)
			(stroke
				(width 0)
				(type default)
			)
			(fill no)
			(layer "F.CrtYd")
		)
		(fp_line
			(start 0.508 -0.3048)
			(end -0.508 -0.3048)
			(stroke
				(width 0.1)
				(type default)
			)
			(layer "F.Fab")
		)
		(fp_line
			(start -0.508 -0.3048)
			(end -0.508 0.3048)
			(stroke
				(width 0.1)
				(type default)
			)
			(layer "F.Fab")
		)
		(fp_line
			(start 0.508 0.3048)
			(end 0.508 -0.3048)
			(stroke
				(width 0.1)
				(type default)
			)
			(layer "F.Fab")
		)
		(fp_line
			(start -0.508 0.3048)
			(end 0.508 0.3048)
			(stroke
				(width 0.1)
				(type default)
			)
			(layer "F.Fab")
		)
		(pad "1" smd rect
			(at -0.5334 0 90)
			(size 0.7112 0.6096)
			(layers "F.Cu" "F.Mask" "F.Paste")
			(net "UNNAMED_524_CONNUSB14PGH4FRATH_")
		)
		(pad "2" smd rect
			(at 0.5334 0 90)
			(size 0.7112 0.6096)
			(layers "F.Cu" "F.Mask" "F.Paste")
			(net "SG")
		)
		(zone
			(layer "F.Cu")
			(hatch none 0.5)
			(connect_pads
				(clearance 0)
			)
			(min_thickness 0.25)
			(keepout
				(tracks allowed)
				(vias not_allowed)
				(pads allowed)
				(copperpour not_allowed)
				(footprints allowed)
			)
			(placement
				(enabled no)
				(sheetname "")
			)
			(fill
				(thermal_gap 0.5)
				(thermal_bridge_width 0.5)
				(island_removal_mode 0)
			)
			(polygon
				(pts
					(xy 15.4178 -90.7288) (xy 15.4178 -90.8812) (xy 14.8082 -90.8812) (xy 14.8082 -90.7288)
				)
			)
		)
		(zone
			(layer "F.Cu")
			(hatch none 0.5)
			(connect_pads
				(clearance 0)
			)
			(min_thickness 0.25)
			(keepout
				(tracks not_allowed)
				(vias allowed)
				(pads allowed)
				(copperpour not_allowed)
				(footprints allowed)
			)
			(placement
				(enabled no)
				(sheetname "")
			)
			(fill
				(thermal_gap 0.5)
				(thermal_bridge_width 0.5)
				(island_removal_mode 0)
			)
			(polygon
				(pts
					(xy 15.4178 -90.7288) (xy 15.4178 -90.8812) (xy 14.8082 -90.8812) (xy 14.8082 -90.7288)
				)
			)
		)
	)
	(footprint ""
		(layer "F.Cu")
		(at 85.979 -54.229 180)
		(property "Reference" "TP61"
			(at 0.5842 -1.56337 0)
			(unlocked yes)
			(layer "F.SilkS")
			(effects
				(font
					(size 0.7874 0.5842)
					(thickness 0.1524)
				)
				(justify left)
			)
		)
		(property "Value" ""
			(at 0 0 180)
			(layer "F.Fab")
			(effects
				(font
					(size 1.27 1.27)
				)
			)
		)
		(property "Device Type" "TP_PIONT-TP010CT020B030_PTH-TPA"
			(at -1.341882 0.996696 180)
			(unlocked yes)
			(layer "F.Fab")
			(hide yes)
			(effects
				(font
					(size 0.7874 0.5842)
					(thickness 0.1524)
				)
				(justify left)
			)
		)
		(duplicate_pad_numbers_are_jumpers no)
		(fp_poly
			(pts
				(arc
					(start -0.889 0)
					(mid 0.889 0)
					(end -0.889 0)
				)
			)
			(stroke
				(width 0)
				(type default)
			)
			(fill no)
			(layer "B.CrtYd")
		)
		(fp_poly
			(pts
				(arc
					(start -0.889 0)
					(mid 0.889 0)
					(end -0.889 0)
				)
			)
			(stroke
				(width 0)
				(type default)
			)
			(fill no)
			(layer "F.CrtYd")
		)
		(pad "1" thru_hole circle
			(at 0 0 180)
			(size 0.508 0.508)
			(drill 0.254)
			(layers "*.Cu" "*.Mask")
			(remove_unused_layers no)
			(net "UNNAMED_9_BNO080LGA28_I29_HCS")
			(clearance 0.1016)
			(padstack
				(mode front_inner_back)
				(layer "Inner"
					(shape circle)
					(size 0.508 0.508)
					(clearance 0.1016)
				)
				(layer "B.Cu"
					(shape circle)
					(size 0.762 0.762)
					(clearance -0.0254)
				)
			)
		)
	)
)
